# S9S_MB_2U (Grand Teton) — schematic netlist excerpt (pin names and nets, part order shuffled) for the footprints in the layout excerpt that follows; sources: Cadence DE-HDL packaged netlist, KiCad conversion of 03242023_DA0F0TMBIJ0_F0T_Motherboard_J_brd_V01_OCP.brd

R1652  Q_RES  0 5% CHIP  pkg 0402LF  page 282 : A = PWRGD_PVNN_MAIN_CPU0_R ; B = PWRGD_PVNN_MAIN_CPU0
C1197  Q_CAP  22UF 4V 20% X6S  pkg C0603  page 189 : A = P1V8_PCH_AUX ; B = GND

(kicad_pcb
	(version 20260206)
	(generator "pcbnew")
	(generator_version "10.0")
	(general
		(thickness 1.6)
		(legacy_teardrops no)
	)
	(paper "A4")
	(title_block
		(title "03242023_DA0F0TMBIJ0_F0T_Motherboard_J_brd_V01_OCP.brd")
		(comment 1 "Grand Teton / footprints 5493-5494 of 6105")
	)
	(layers
		(0 "F.Cu" signal "TOP")
		(4 "In1.Cu" signal "GND")
		(6 "In2.Cu" signal "IN1")
		(8 "In3.Cu" signal "GND1")
		(10 "In4.Cu" signal "IN2")
		(12 "In5.Cu" signal "GND2")
		(14 "In6.Cu" signal "IN3")
		(16 "In7.Cu" signal "GND3")
		(18 "In8.Cu" signal "VCC")
		(20 "In9.Cu" signal "VCC1")
		(22 "In10.Cu" signal "GND4")
		(24 "In11.Cu" signal "IN4")
		(26 "In12.Cu" signal "GND5")
		(28 "In13.Cu" signal "IN5")
		(30 "In14.Cu" signal "GND6")
		(32 "In15.Cu" signal "IN6")
		(34 "In16.Cu" signal "GND7")
		(2 "B.Cu" signal "BOTTOM")
		(9 "F.Adhes" user "F.Adhesive")
		(11 "B.Adhes" user "B.Adhesive")
		(13 "F.Paste" user "Package Geometry/Pastemask Top")
		(15 "B.Paste" user "Package Geometry/Pastemask Bottom")
		(5 "F.SilkS" user "Ref Des/Silkscreen Top")
		(7 "B.SilkS" user "Ref Des/Silkscreen Bottom")
		(1 "F.Mask" user "Board Geometry/Soldermask Top")
		(3 "B.Mask" user "Board Geometry/Soldermask Bottom")
		(17 "Dwgs.User" user "User.Drawings")
		(19 "Cmts.User" user "User.Comments")
		(21 "Eco1.User" user "User.Eco1")
		(23 "Eco2.User" user "User.Eco2")
		(25 "Edge.Cuts" user "Board Geometry/Outline")
		(27 "Margin" user)
		(31 "F.CrtYd" user "Package Geometry/Place Bound Top")
		(29 "B.CrtYd" user "Package Geometry/Place Bound Bottom")
		(35 "F.Fab" user "Ref Des/Assembly Top")
		(33 "B.Fab" user "Ref Des/Assembly Bottom")
	)
	(footprint ""
		(layer "B.Cu")
		(at 334.931258 -58.465466 -90)
		(property "Reference" "C1197"
			(at 0 0 90)
			(layer "B.SilkS")
			(hide yes)
			(effects
				(font
					(size 1.27 1.27)
				)
				(justify mirror)
			)
		)
		(property "Value" ""
			(at 0 0 90)
			(layer "B.Fab")
			(effects
				(font
					(size 1.27 1.27)
				)
				(justify mirror)
			)
		)
		(duplicate_pad_numbers_are_jumpers no)
		(fp_line
			(start -1.2954 0.5842)
			(end 1.2954 0.5842)
			(stroke
				(width 0.1524)
				(type default)
			)
			(layer "B.SilkS")
		)
		(fp_line
			(start 1.2954 0.5842)
			(end 1.2954 -0.5842)
			(stroke
				(width 0.1524)
				(type default)
			)
			(layer "B.SilkS")
		)
		(fp_line
			(start -1.2954 -0.5842)
			(end -1.2954 0.5842)
			(stroke
				(width 0.1524)
				(type default)
			)
			(layer "B.SilkS")
		)
		(fp_line
			(start 0 -0.5842)
			(end 0 0.5842)
			(stroke
				(width 0.1524)
				(type default)
			)
			(layer "B.SilkS")
		)
		(fp_line
			(start 1.2954 -0.5842)
			(end -1.2954 -0.5842)
			(stroke
				(width 0.1524)
				(type default)
			)
			(layer "B.SilkS")
		)
		(fp_line
			(start -0.8636 0.4572)
			(end 0.8636 0.4572)
			(stroke
				(width 0.1)
				(type default)
			)
			(layer "B.Fab")
		)
		(fp_line
			(start 0.8636 0.4572)
			(end 0.8636 0.4064)
			(stroke
				(width 0.1)
				(type default)
			)
			(layer "B.Fab")
		)
		(fp_line
			(start -1.1938 0.4064)
			(end -0.8636 0.4064)
			(stroke
				(width 0.1)
				(type default)
			)
			(layer "B.Fab")
		)
		(fp_line
			(start -0.8636 0.4064)
			(end -0.8636 0.4572)
			(stroke
				(width 0.1)
				(type default)
			)
			(layer "B.Fab")
		)
		(fp_line
			(start 0.8636 0.4064)
			(end 1.1938 0.4064)
			(stroke
				(width 0.1)
				(type default)
			)
			(layer "B.Fab")
		)
		(fp_line
			(start 1.1938 0.4064)
			(end 1.1938 -0.4064)
			(stroke
				(width 0.1)
				(type default)
			)
			(layer "B.Fab")
		)
		(fp_line
			(start -1.1938 -0.4064)
			(end -1.1938 0.4064)
			(stroke
				(width 0.1)
				(type default)
			)
			(layer "B.Fab")
		)
		(fp_line
			(start -0.8636 -0.4064)
			(end -1.1938 -0.4064)
			(stroke
				(width 0.1)
				(type default)
			)
			(layer "B.Fab")
		)
		(fp_line
			(start 0.8636 -0.4064)
			(end 0.8636 -0.4572)
			(stroke
				(width 0.1)
				(type default)
			)
			(layer "B.Fab")
		)
		(fp_line
			(start 1.1938 -0.4064)
			(end 0.8636 -0.4064)
			(stroke
				(width 0.1)
				(type default)
			)
			(layer "B.Fab")
		)
		(fp_line
			(start -0.8636 -0.4572)
			(end -0.8636 -0.4064)
			(stroke
				(width 0.1)
				(type default)
			)
			(layer "B.Fab")
		)
		(fp_line
			(start 0.8636 -0.4572)
			(end -0.8636 -0.4572)
			(stroke
				(width 0.1)
				(type default)
			)
			(layer "B.Fab")
		)
		(pad "1" smd rect
			(at 0.7366 0 180)
			(size 0.7112 0.8128)
			(layers "B.Cu" "B.Mask" "B.Paste")
			(net "P1V8_PCH_AUX")
		)
		(pad "2" smd rect
			(at -0.7366 0 180)
			(size 0.7112 0.8128)
			(layers "B.Cu" "B.Mask" "B.Paste")
			(net "GND")
		)
	)
	(footprint ""
		(layer "B.Cu")
		(at 434.209444 -180.971698 -90)
		(property "Reference" "R1652"
			(at 0 0 90)
			(layer "B.SilkS")
			(hide yes)
			(effects
				(font
					(size 1.27 1.27)
				)
				(justify mirror)
			)
		)
		(property "Value" ""
			(at 0 0 90)
			(layer "B.Fab")
			(effects
				(font
					(size 1.27 1.27)
				)
				(justify mirror)
			)
		)
		(duplicate_pad_numbers_are_jumpers no)
		(fp_line
			(start -0.7874 0.4064)
			(end 0.7874 0.4064)
			(stroke
				(width 0.1524)
				(type default)
			)
			(layer "B.SilkS")
		)
		(fp_line
			(start 0.7874 0.4064)
			(end 0.7874 -0.4064)
			(stroke
				(width 0.1524)
				(type default)
			)
			(layer "B.SilkS")
		)
		(fp_line
			(start -0.7874 -0.4064)
			(end -0.7874 0.4064)
			(stroke
				(width 0.1524)
				(type default)
			)
			(layer "B.SilkS")
		)
		(fp_line
			(start 0.7874 -0.4064)
			(end -0.7874 -0.4064)
			(stroke
				(width 0.1524)
				(type default)
			)
			(layer "B.SilkS")
		)
		(fp_line
			(start -0.67945 0.3048)
			(end -0.120396 0.3048)
			(stroke
				(width 0.1)
				(type default)
			)
			(layer "B.Fab")
		)
		(fp_line
			(start -0.120396 0.3048)
			(end -0.120396 0.2794)
			(stroke
				(width 0.1)
				(type default)
			)
			(layer "B.Fab")
		)
		(fp_line
			(start 0.12065 0.3048)
			(end 0.67945 0.3048)
			(stroke
				(width 0.1)
				(type default)
			)
			(layer "B.Fab")
		)
		(fp_line
			(start 0.67945 0.3048)
			(end 0.67945 -0.305054)
			(stroke
				(width 0.1)
				(type default)
			)
			(layer "B.Fab")
		)
		(fp_line
			(start -0.120396 0.2794)
			(end 0.12065 0.2794)
			(stroke
				(width 0.1)
				(type default)
			)
			(layer "B.Fab")
		)
		(fp_line
			(start 0.12065 0.2794)
			(end 0.12065 0.3048)
			(stroke
				(width 0.1)
				(type default)
			)
			(layer "B.Fab")
		)
		(fp_line
			(start -0.12065 -0.2794)
			(end -0.12065 -0.3048)
			(stroke
				(width 0.1)
				(type default)
			)
			(layer "B.Fab")
		)
		(fp_line
			(start 0.12065 -0.2794)
			(end -0.12065 -0.2794)
			(stroke
				(width 0.1)
				(type default)
			)
			(layer "B.Fab")
		)
		(fp_line
			(start -0.67945 -0.3048)
			(end -0.67945 0.3048)
			(stroke
				(width 0.1)
				(type default)
			)
			(layer "B.Fab")
		)
		(fp_line
			(start -0.12065 -0.3048)
			(end -0.67945 -0.3048)
			(stroke
				(width 0.1)
				(type default)
			)
			(layer "B.Fab")
		)
		(fp_line
			(start 0.12065 -0.305054)
			(end 0.12065 -0.2794)
			(stroke
				(width 0.1)
				(type default)
			)
			(layer "B.Fab")
		)
		(fp_line
			(start 0.67945 -0.305054)
			(end 0.12065 -0.305054)
			(stroke
				(width 0.1)
				(type default)
			)
			(layer "B.Fab")
		)
		(pad "1" smd circle
			(at 0.40005 0 90)
			(size 0 0)
			(layers "B.Cu" "B.Mask" "B.Paste")
			(net "PWRGD_PVNN_MAIN_CPU0_R")
		)
		(pad "2" smd circle
			(at -0.40005 0 90)
			(size 0 0)
			(layers "B.Cu" "B.Mask" "B.Paste")
			(net "PWRGD_PVNN_MAIN_CPU0")
		)
	)
)
